(kicad_pcb
	(version 20260206)
	(generator "pcbnew")
	(generator_version "10.0")
	(general
		(thickness 1.6)
		(legacy_teardrops no)
	)
	(paper "A4")
	(title_block
		(title "01162023_DA0F0TEBIF0_F0T_Expander_BD_F_brd_V02_OCP.brd")
		(comment 1 "Grand Teton / footprints 3282-3287 of 9728")
	)
	(layers
		(0 "F.Cu" signal "TOP")
		(4 "In1.Cu" signal "GND")
		(6 "In2.Cu" signal "VCC")
		(8 "In3.Cu" signal "VCC1")
		(10 "In4.Cu" signal "GND1")
		(12 "In5.Cu" signal "IN1")
		(14 "In6.Cu" signal "GND2")
		(16 "In7.Cu" signal "IN2")
		(18 "In8.Cu" signal "GND3")
		(20 "In9.Cu" signal "IN3")
		(22 "In10.Cu" signal "GND4")
		(24 "In11.Cu" signal "IN4")
		(26 "In12.Cu" signal "GND5")
		(28 "In13.Cu" signal "IN5")
		(30 "In14.Cu" signal "GND6")
		(32 "In15.Cu" signal "IN6")
		(34 "In16.Cu" signal "GND7")
		(2 "B.Cu" signal "BOTTOM")
		(9 "F.Adhes" user "F.Adhesive")
		(11 "B.Adhes" user "B.Adhesive")
		(13 "F.Paste" user "Package Geometry/Pastemask Top")
		(15 "B.Paste" user "Package Geometry/Pastemask Bottom")
		(5 "F.SilkS" user "Ref Des/Silkscreen Top")
		(7 "B.SilkS" user "Ref Des/Silkscreen Bottom")
		(1 "F.Mask" user "Board Geometry/Soldermask Top")
		(3 "B.Mask" user "Board Geometry/Soldermask Bottom")
		(17 "Dwgs.User" user "User.Drawings")
		(19 "Cmts.User" user "User.Comments")
		(21 "Eco1.User" user "User.Eco1")
		(23 "Eco2.User" user "User.Eco2")
		(25 "Edge.Cuts" user "Board Geometry/Outline")
		(27 "Margin" user)
		(31 "F.CrtYd" user "Package Geometry/Place Bound Top")
		(29 "B.CrtYd" user "Package Geometry/Place Bound Bottom")
		(35 "F.Fab" user "Ref Des/Assembly Top")
		(33 "B.Fab" user "Ref Des/Assembly Bottom")
	)
	(footprint ""
		(layer "F.Cu")
		(at 95.622618 -22.867366 90)
		(property "Reference" "C3894"
			(at 0 0 90)
			(layer "F.SilkS")
			(hide yes)
			(effects
				(font
					(size 1.27 1.27)
				)
			)
		)
		(property "Value" ""
			(at 0 0 90)
			(layer "F.Fab")
			(effects
				(font
					(size 1.27 1.27)
				)
			)
		)
		(duplicate_pad_numbers_are_jumpers no)
		(fp_line
			(start 0.7874 -0.4064)
			(end 0.7874 0.4064)
			(stroke
				(width 0.1524)
				(type default)
			)
			(layer "F.SilkS")
		)
		(fp_line
			(start -0.7874 -0.4064)
			(end 0.7874 -0.4064)
			(stroke
				(width 0.1524)
				(type default)
			)
			(layer "F.SilkS")
		)
		(fp_line
			(start 0.7874 0.4064)
			(end -0.7874 0.4064)
			(stroke
				(width 0.1524)
				(type default)
			)
			(layer "F.SilkS")
		)
		(fp_line
			(start -0.7874 0.4064)
			(end -0.7874 -0.4064)
			(stroke
				(width 0.1524)
				(type default)
			)
			(layer "F.SilkS")
		)
		(fp_line
			(start -0.12065 -0.305054)
			(end -0.12065 -0.2794)
			(stroke
				(width 0.1)
				(type default)
			)
			(layer "F.Fab")
		)
		(fp_line
			(start -0.67945 -0.305054)
			(end -0.12065 -0.305054)
			(stroke
				(width 0.1)
				(type default)
			)
			(layer "F.Fab")
		)
		(fp_line
			(start 0.67945 -0.3048)
			(end 0.67945 0.3048)
			(stroke
				(width 0.1)
				(type default)
			)
			(layer "F.Fab")
		)
		(fp_line
			(start 0.12065 -0.3048)
			(end 0.67945 -0.3048)
			(stroke
				(width 0.1)
				(type default)
			)
			(layer "F.Fab")
		)
		(fp_line
			(start 0.12065 -0.2794)
			(end 0.12065 -0.3048)
			(stroke
				(width 0.1)
				(type default)
			)
			(layer "F.Fab")
		)
		(fp_line
			(start -0.12065 -0.2794)
			(end 0.12065 -0.2794)
			(stroke
				(width 0.1)
				(type default)
			)
			(layer "F.Fab")
		)
		(fp_line
			(start 0.120396 0.2794)
			(end -0.12065 0.2794)
			(stroke
				(width 0.1)
				(type default)
			)
			(layer "F.Fab")
		)
		(fp_line
			(start -0.12065 0.2794)
			(end -0.12065 0.3048)
			(stroke
				(width 0.1)
				(type default)
			)
			(layer "F.Fab")
		)
		(fp_line
			(start 0.67945 0.3048)
			(end 0.120396 0.3048)
			(stroke
				(width 0.1)
				(type default)
			)
			(layer "F.Fab")
		)
		(fp_line
			(start 0.120396 0.3048)
			(end 0.120396 0.2794)
			(stroke
				(width 0.1)
				(type default)
			)
			(layer "F.Fab")
		)
		(fp_line
			(start -0.12065 0.3048)
			(end -0.67945 0.3048)
			(stroke
				(width 0.1)
				(type default)
			)
			(layer "F.Fab")
		)
		(fp_line
			(start -0.67945 0.3048)
			(end -0.67945 -0.305054)
			(stroke
				(width 0.1)
				(type default)
			)
			(layer "F.Fab")
		)
		(pad "1" smd circle
			(at -0.40005 0 90)
			(size 0 0)
			(layers "F.Cu" "F.Mask" "F.Paste")
			(net "P12V_SSD3")
		)
		(pad "2" smd circle
			(at 0.40005 0 90)
			(size 0 0)
			(layers "F.Cu" "F.Mask" "F.Paste")
			(net "GND")
		)
	)
	(footprint ""
		(layer "F.Cu")
		(at 436.307484 -96.811592 -90)
		(property "Reference" "R762"
			(at 0 0 270)
			(layer "F.SilkS")
			(hide yes)
			(effects
				(font
					(size 1.27 1.27)
				)
			)
		)
		(property "Value" ""
			(at 0 0 270)
			(layer "F.Fab")
			(effects
				(font
					(size 1.27 1.27)
				)
			)
		)
		(duplicate_pad_numbers_are_jumpers no)
		(fp_line
			(start -0.7874 0.4064)
			(end -0.7874 -0.4064)
			(stroke
				(width 0.1524)
				(type default)
			)
			(layer "F.SilkS")
		)
		(fp_line
			(start 0.7874 0.4064)
			(end -0.7874 0.4064)
			(stroke
				(width 0.1524)
				(type default)
			)
			(layer "F.SilkS")
		)
		(fp_line
			(start -0.7874 -0.4064)
			(end 0.7874 -0.4064)
			(stroke
				(width 0.1524)
				(type default)
			)
			(layer "F.SilkS")
		)
		(fp_line
			(start 0.7874 -0.4064)
			(end 0.7874 0.4064)
			(stroke
				(width 0.1524)
				(type default)
			)
			(layer "F.SilkS")
		)
		(fp_line
			(start -0.67945 0.3048)
			(end -0.67945 -0.305054)
			(stroke
				(width 0.1)
				(type default)
			)
			(layer "F.Fab")
		)
		(fp_line
			(start -0.12065 0.3048)
			(end -0.67945 0.3048)
			(stroke
				(width 0.1)
				(type default)
			)
			(layer "F.Fab")
		)
		(fp_line
			(start 0.120396 0.3048)
			(end 0.120396 0.2794)
			(stroke
				(width 0.1)
				(type default)
			)
			(layer "F.Fab")
		)
		(fp_line
			(start 0.67945 0.3048)
			(end 0.120396 0.3048)
			(stroke
				(width 0.1)
				(type default)
			)
			(layer "F.Fab")
		)
		(fp_line
			(start -0.12065 0.2794)
			(end -0.12065 0.3048)
			(stroke
				(width 0.1)
				(type default)
			)
			(layer "F.Fab")
		)
		(fp_line
			(start 0.120396 0.2794)
			(end -0.12065 0.2794)
			(stroke
				(width 0.1)
				(type default)
			)
			(layer "F.Fab")
		)
		(fp_line
			(start -0.12065 -0.2794)
			(end 0.12065 -0.2794)
			(stroke
				(width 0.1)
				(type default)
			)
			(layer "F.Fab")
		)
		(fp_line
			(start 0.12065 -0.2794)
			(end 0.12065 -0.3048)
			(stroke
				(width 0.1)
				(type default)
			)
			(layer "F.Fab")
		)
		(fp_line
			(start 0.12065 -0.3048)
			(end 0.67945 -0.3048)
			(stroke
				(width 0.1)
				(type default)
			)
			(layer "F.Fab")
		)
		(fp_line
			(start 0.67945 -0.3048)
			(end 0.67945 0.3048)
			(stroke
				(width 0.1)
				(type default)
			)
			(layer "F.Fab")
		)
		(fp_line
			(start -0.67945 -0.305054)
			(end -0.12065 -0.305054)
			(stroke
				(width 0.1)
				(type default)
			)
			(layer "F.Fab")
		)
		(fp_line
			(start -0.12065 -0.305054)
			(end -0.12065 -0.2794)
			(stroke
				(width 0.1)
				(type default)
			)
			(layer "F.Fab")
		)
		(pad "1" smd circle
			(at -0.40005 0 270)
			(size 0 0)
			(layers "F.Cu" "F.Mask" "F.Paste")
			(net "NIC7_ADC_A1")
		)
		(pad "2" smd circle
			(at 0.40005 0 270)
			(size 0 0)
			(layers "F.Cu" "F.Mask" "F.Paste")
			(net "GND")
		)
	)
	(footprint ""
		(layer "F.Cu")
		(at 377.3805 -343.952322 90)
		(property "Reference" "C766"
			(at 0 0 90)
			(layer "F.SilkS")
			(hide yes)
			(effects
				(font
					(size 1.27 1.27)
				)
			)
		)
		(property "Value" ""
			(at 0 0 90)
			(layer "F.Fab")
			(effects
				(font
					(size 1.27 1.27)
				)
			)
		)
		(duplicate_pad_numbers_are_jumpers no)
		(fp_line
			(start 0.299974 -0.150114)
			(end 0.299974 0.150114)
			(stroke
				(width 0.1)
				(type default)
			)
			(layer "F.Fab")
		)
		(fp_line
			(start -0.299974 -0.150114)
			(end 0.299974 -0.150114)
			(stroke
				(width 0.1)
				(type default)
			)
			(layer "F.Fab")
		)
		(fp_line
			(start 0.299974 0.150114)
			(end -0.299974 0.150114)
			(stroke
				(width 0.1)
				(type default)
			)
			(layer "F.Fab")
		)
		(fp_line
			(start -0.299974 0.150114)
			(end -0.299974 -0.150114)
			(stroke
				(width 0.1)
				(type default)
			)
			(layer "F.Fab")
		)
		(pad "1" smd rect
			(at -0.2667 0 90)
			(size 0.3048 0.381)
			(layers "F.Cu" "F.Mask" "F.Paste")
			(net "P5E_PEX3_STN6_TX_DP<109>")
		)
		(pad "2" smd rect
			(at 0.2667 0 90)
			(size 0.3048 0.381)
			(layers "F.Cu" "F.Mask" "F.Paste")
			(net "P5E_PEX3_STN6_TX_C_DP<109>")
		)
	)
	(footprint ""
		(layer "F.Cu")
		(at 136.534652 -30.94609 180)
		(property "Reference" "C280"
			(at 0 0 180)
			(layer "F.SilkS")
			(hide yes)
			(effects
				(font
					(size 1.27 1.27)
				)
			)
		)
		(property "Value" ""
			(at 0 0 180)
			(layer "F.Fab")
			(effects
				(font
					(size 1.27 1.27)
				)
			)
		)
		(duplicate_pad_numbers_are_jumpers no)
		(fp_line
			(start 0.299974 0.150114)
			(end -0.299974 0.150114)
			(stroke
				(width 0.1)
				(type default)
			)
			(layer "F.Fab")
		)
		(fp_line
			(start 0.299974 -0.150114)
			(end 0.299974 0.150114)
			(stroke
				(width 0.1)
				(type default)
			)
			(layer "F.Fab")
		)
		(fp_line
			(start -0.299974 0.150114)
			(end -0.299974 -0.150114)
			(stroke
				(width 0.1)
				(type default)
			)
			(layer "F.Fab")
		)
		(fp_line
			(start -0.299974 -0.150114)
			(end 0.299974 -0.150114)
			(stroke
				(width 0.1)
				(type default)
			)
			(layer "F.Fab")
		)
		(pad "1" smd rect
			(at -0.2667 0 180)
			(size 0.3048 0.381)
			(layers "F.Cu" "F.Mask" "F.Paste")
			(net "P5E_PEX1_STN2_TX_DP<45>")
		)
		(pad "2" smd rect
			(at 0.2667 0 180)
			(size 0.3048 0.381)
			(layers "F.Cu" "F.Mask" "F.Paste")
			(net "P5E_PEX1_STN2_TX_C_DP<45>")
		)
	)
	(footprint ""
		(layer "F.Cu")
		(at 243.93271 -162.003994 90)
		(property "Reference" "PC814"
			(at 0 0 90)
			(layer "F.SilkS")
			(hide yes)
			(effects
				(font
					(size 1.27 1.27)
				)
			)
		)
		(property "Value" ""
			(at 0 0 90)
			(layer "F.Fab")
			(effects
				(font
					(size 1.27 1.27)
				)
			)
		)
		(duplicate_pad_numbers_are_jumpers no)
		(fp_line
			(start 0.7874 -0.4064)
			(end 0.7874 0.4064)
			(stroke
				(width 0.1524)
				(type default)
			)
			(layer "F.SilkS")
		)
		(fp_line
			(start -0.7874 -0.4064)
			(end 0.7874 -0.4064)
			(stroke
				(width 0.1524)
				(type default)
			)
			(layer "F.SilkS")
		)
		(fp_line
			(start 0.7874 0.4064)
			(end -0.7874 0.4064)
			(stroke
				(width 0.1524)
				(type default)
			)
			(layer "F.SilkS")
		)
		(fp_line
			(start -0.7874 0.4064)
			(end -0.7874 -0.4064)
			(stroke
				(width 0.1524)
				(type default)
			)
			(layer "F.SilkS")
		)
		(fp_line
			(start -0.12065 -0.305054)
			(end -0.12065 -0.2794)
			(stroke
				(width 0.1)
				(type default)
			)
			(layer "F.Fab")
		)
		(fp_line
			(start -0.67945 -0.305054)
			(end -0.12065 -0.305054)
			(stroke
				(width 0.1)
				(type default)
			)
			(layer "F.Fab")
		)
		(fp_line
			(start 0.67945 -0.3048)
			(end 0.67945 0.3048)
			(stroke
				(width 0.1)
				(type default)
			)
			(layer "F.Fab")
		)
		(fp_line
			(start 0.12065 -0.3048)
			(end 0.67945 -0.3048)
			(stroke
				(width 0.1)
				(type default)
			)
			(layer "F.Fab")
		)
		(fp_line
			(start 0.12065 -0.2794)
			(end 0.12065 -0.3048)
			(stroke
				(width 0.1)
				(type default)
			)
			(layer "F.Fab")
		)
		(fp_line
			(start -0.12065 -0.2794)
			(end 0.12065 -0.2794)
			(stroke
				(width 0.1)
				(type default)
			)
			(layer "F.Fab")
		)
		(fp_line
			(start 0.120396 0.2794)
			(end -0.12065 0.2794)
			(stroke
				(width 0.1)
				(type default)
			)
			(layer "F.Fab")
		)
		(fp_line
			(start -0.12065 0.2794)
			(end -0.12065 0.3048)
			(stroke
				(width 0.1)
				(type default)
			)
			(layer "F.Fab")
		)
		(fp_line
			(start 0.67945 0.3048)
			(end 0.120396 0.3048)
			(stroke
				(width 0.1)
				(type default)
			)
			(layer "F.Fab")
		)
		(fp_line
			(start 0.120396 0.3048)
			(end 0.120396 0.2794)
			(stroke
				(width 0.1)
				(type default)
			)
			(layer "F.Fab")
		)
		(fp_line
			(start -0.12065 0.3048)
			(end -0.67945 0.3048)
			(stroke
				(width 0.1)
				(type default)
			)
			(layer "F.Fab")
		)
		(fp_line
			(start -0.67945 0.3048)
			(end -0.67945 -0.305054)
			(stroke
				(width 0.1)
				(type default)
			)
			(layer "F.Fab")
		)
		(pad "1" smd circle
			(at -0.40005 0 90)
			(size 0 0)
			(layers "F.Cu" "F.Mask" "F.Paste")
			(net "P12V_NIC4_CO_ISET_R")
		)
		(pad "2" smd circle
			(at 0.40005 0 90)
			(size 0 0)
			(layers "F.Cu" "F.Mask" "F.Paste")
			(net "GND")
		)
	)
	(footprint ""
		(layer "F.Cu")
		(at 240.76914 -308.568598 180)
		(property "Reference" "PU18"
			(at 3.535426 -3.834638 0)
			(unlocked yes)
			(layer "F.SilkS")
			(effects
				(font
					(size 0.7874 0.5842)
					(thickness 0.1524)
				)
				(justify left)
			)
		)
		(property "Value" ""
			(at 0 0 180)
			(layer "F.Fab")
			(effects
				(font
					(size 1.27 1.27)
				)
			)
		)
		(duplicate_pad_numbers_are_jumpers no)
		(fp_line
			(start 1.549908 2.050034)
			(end 1.549908 1.9304)
			(stroke
				(width 0.1524)
				(type default)
			)
			(layer "F.SilkS")
		)
		(fp_line
			(start 1.549908 -1.9812)
			(end 1.549908 -2.050034)
			(stroke
				(width 0.1524)
				(type default)
			)
			(layer "F.SilkS")
		)
		(fp_line
			(start 1.549908 -2.050034)
			(end 0.5842 -2.050034)
			(stroke
				(width 0.1524)
				(type default)
			)
			(layer "F.SilkS")
		)
		(fp_line
			(start 0.3048 -2.4638)
			(end 0.3048 -3.2258)
			(stroke
				(width 0.1524)
				(type default)
			)
			(layer "F.SilkS")
		)
		(fp_line
			(start 0 2.050034)
			(end 1.549908 2.050034)
			(stroke
				(width 0.1524)
				(type default)
			)
			(layer "F.SilkS")
		)
		(fp_line
			(start -0.3048 2.4638)
			(end -0.3048 3.2258)
			(stroke
				(width 0.1524)
				(type default)
			)
			(layer "F.SilkS")
		)
		(fp_line
			(start -0.5842 -2.050034)
			(end -1.549908 -2.050034)
			(stroke
				(width 0.1524)
				(type default)
			)
			(layer "F.SilkS")
		)
		(fp_line
			(start -1.549908 2.050034)
			(end -0.5842 2.050034)
			(stroke
				(width 0.1524)
				(type default)
			)
			(layer "F.SilkS")
		)
		(fp_line
			(start -1.549908 1.9812)
			(end -1.549908 2.050034)
			(stroke
				(width 0.1524)
				(type default)
			)
			(layer "F.SilkS")
		)
		(fp_line
			(start -1.549908 -2.050034)
			(end -1.549908 -1.9812)
			(stroke
				(width 0.1524)
				(type default)
			)
			(layer "F.SilkS")
		)
		(fp_line
			(start -1.9812 0)
			(end -2.3622 0)
			(stroke
				(width 0.1524)
				(type default)
			)
			(layer "F.SilkS")
		)
		(fp_poly
			(pts
				(xy -2.9464 -2.208022) (xy -2.9464 -1.192022) (xy -1.9304 -1.700022)
			)
			(stroke
				(width 0)
				(type default)
			)
			(fill yes)
			(layer "F.SilkS")
		)
		(fp_line
			(start 1.549908 2.050034)
			(end 1.549908 -2.050034)
			(stroke
				(width 0.1)
				(type default)
			)
			(layer "F.Fab")
		)
		(fp_line
			(start 1.549908 -2.050034)
			(end -1.549908 -2.050034)
			(stroke
				(width 0.1)
				(type default)
			)
			(layer "F.Fab")
		)
		(fp_line
			(start 0.3048 -2.4638)
			(end 0.3048 -3.2258)
			(stroke
				(width 0.1)
				(type default)
			)
			(layer "F.Fab")
		)
		(fp_line
			(start -0.3048 2.4638)
			(end -0.3048 3.2258)
			(stroke
				(width 0.1)
				(type default)
			)
			(layer "F.Fab")
		)
		(fp_line
			(start -1.549908 2.050034)
			(end 1.549908 2.050034)
			(stroke
				(width 0.1)
				(type default)
			)
			(layer "F.Fab")
		)
		(fp_line
			(start -1.549908 -2.050034)
			(end -1.549908 2.050034)
			(stroke
				(width 0.1)
				(type default)
			)
			(layer "F.Fab")
		)
		(fp_line
			(start -1.9812 0)
			(end -2.3622 0)
			(stroke
				(width 0.1)
				(type default)
			)
			(layer "F.Fab")
		)
		(fp_poly
			(pts
				(xy -2.9464 -2.208022) (xy -2.9464 -1.192022) (xy -1.9304 -1.700022)
			)
			(stroke
				(width 0)
				(type default)
			)
			(fill yes)
			(layer "F.Fab")
		)
		(fp_text user "11_18"
			(at 2.512568 0.9906 90)
			(unlocked yes)
			(layer "F.SilkS")
			(effects
				(font
					(size 0.635 0.4064)
					(thickness 0.1524)
				)
			)
		)
		(fp_text user "19"
			(at 1.88849 -2.600198 90)
			(unlocked yes)
			(layer "F.SilkS")
			(effects
				(font
					(size 0.635 0.4064)
					(thickness 0.1524)
				)
			)
		)
		(fp_text user "9"
			(at -1.81991 2.378202 90)
			(unlocked yes)
			(layer "F.SilkS")
			(effects
				(font
					(size 0.635 0.4064)
					(thickness 0.1524)
				)
			)
		)
		(fp_text user "11_18"
			(at 2.512568 0.9906 90)
			(unlocked yes)
			(layer "F.Fab")
			(effects
				(font
					(size 0.635 0.4064)
					(thickness 0.1524)
				)
			)
		)
		(fp_text user "19"
			(at 2.410968 -2.159 90)
			(unlocked yes)
			(layer "F.Fab")
			(effects
				(font
					(size 0.635 0.4064)
					(thickness 0.1524)
				)
			)
		)
		(fp_text user "9"
			(at -2.338832 2.0574 90)
			(unlocked yes)
			(layer "F.Fab")
			(effects
				(font
					(size 0.635 0.4064)
					(thickness 0.1524)
				)
			)
		)
		(pad "1" smd rect
			(at -1.35001 -1.700022 270)
			(size 0.3048 0.9144)
			(layers "F.Cu" "F.Mask" "F.Paste")
			(net "SW_P1V25_PEX2_BT")
		)
		(pad "2" smd rect
			(at -1.400048 -1.199896 270)
			(size 0.1778 0.8128)
			(layers "F.Cu" "F.Mask" "F.Paste")
			(net "GND")
		)
		(pad "3" smd rect
			(at -1.400048 -0.8001 270)
			(size 0.1778 0.8128)
			(layers "F.Cu" "F.Mask" "F.Paste")
			(net "P1V25_PEX2_CS")
		)
		(pad "4" smd rect
			(at -1.400048 -0.40005 270)
			(size 0.1778 0.8128)
			(layers "F.Cu" "F.Mask" "F.Paste")
			(net "GND")
		)
		(pad "5" smd rect
			(at -1.400048 0 270)
			(size 0.1778 0.8128)
			(layers "F.Cu" "F.Mask" "F.Paste")
			(net "P1V25_PEX2_REF")
		)
		(pad "6" smd rect
			(at -1.400048 0.40005 270)
			(size 0.1778 0.8128)
			(layers "F.Cu" "F.Mask" "F.Paste")
			(net "SH_P1V25_PEX2_FB_N")
		)
		(pad "7" smd rect
			(at -1.400048 0.8001 270)
			(size 0.1778 0.8128)
			(layers "F.Cu" "F.Mask" "F.Paste")
			(net "P1V25_PEX2_FB")
		)
		(pad "8" smd rect
			(at -1.400048 1.199896 270)
			(size 0.1778 0.8128)
			(layers "F.Cu" "F.Mask" "F.Paste")
			(net "P1V25_PEX2_EN")
		)
		(pad "9" smd rect
			(at -1.400048 1.700022 270)
			(size 0.3048 0.8128)
			(layers "F.Cu" "F.Mask" "F.Paste")
			(net "PWRGD_P1V25_PEX2")
		)
		(pad "10" smd rect
			(at -0.299974 1.299972 180)
			(size 0.3048 2.0066)
			(layers "F.Cu" "F.Mask" "F.Paste")
			(net "SW_P12V_P1V25_PEX2_FLT")
		)
		(pad "11_18" smd circle
			(at 1.175004 0.275082 180)
			(size 0 0)
			(layers "F.Cu" "F.Mask" "F.Paste")
			(net "GND")
		)
		(pad "19" smd rect
			(at 1.400048 -1.700022 90)
			(size 0.3048 0.8128)
			(layers "F.Cu" "F.Mask" "F.Paste")
			(net "P1V25_PEX2_VCC")
		)
		(pad "20" smd rect
			(at 0.299974 -1.299972 180)
			(size 0.3048 2.0066)
			(layers "F.Cu" "F.Mask" "F.Paste")
			(net "SW_P1V25_PEX2_PH")
		)
		(pad "21" smd rect
			(at -0.299974 -1.299972 180)
			(size 0.3048 2.0066)
			(layers "F.Cu" "F.Mask" "F.Paste")
			(net "SW_P12V_P1V25_PEX2_FLT")
		)
	)
)
